FILE_TYPE = CONNECTIVITY;
{Allegro Design Entry HDL 17.2-2016 S066 (3851973) 4/6/2020}
"PAGE_NUMBER" = 526;
0"NC";
END.
